# T6G (Grand Teton) — schematic netlist excerpt (pin names and nets, part order shuffled) for the footprints in the layout excerpt that follows; sources: Cadence DE-HDL packaged netlist, KiCad conversion of 04192023_DAF0TMB3IC0_F0TG_MB_C_brd_V02_OCP.brd

PC273  Q_CAPP  270UF 16V 20% OSCON  pkg THLF  page 211 : A = SW_P12V_AUX_PVDDCR_CPU0_P1_FLT ; B = GND
R1619  Q_RES  0 5% CHIP  pkg 0402LF  page 172 : A = JTAG_BMC_OE ; B = JTAG_BMC_R_D_OE
PD112  SCHOTTKY_AC  B340A-13-F IC  pkg D2010XF  page 146 : A = GND ; C = P12V_E1S_0

(kicad_pcb
	(version 20260206)
	(generator "pcbnew")
	(generator_version "10.0")
	(general
		(thickness 1.6)
		(legacy_teardrops no)
	)
	(paper "A4")
	(title_block
		(title "04192023_DAF0TMB3IC0_F0TG_MB_C_brd_V02_OCP.brd")
		(comment 1 "Grand Teton / footprints 383-385 of 8354")
	)
	(layers
		(0 "F.Cu" signal "TOP")
		(4 "In1.Cu" signal "GND")
		(6 "In2.Cu" signal "IN1")
		(8 "In3.Cu" signal "GND1")
		(10 "In4.Cu" signal "IN2")
		(12 "In5.Cu" signal "GND2")
		(14 "In6.Cu" signal "IN3")
		(16 "In7.Cu" signal "GND3")
		(18 "In8.Cu" signal "VCC")
		(20 "In9.Cu" signal "VCC1")
		(22 "In10.Cu" signal "GND4")
		(24 "In11.Cu" signal "IN4")
		(26 "In12.Cu" signal "GND5")
		(28 "In13.Cu" signal "IN5")
		(30 "In14.Cu" signal "GND6")
		(32 "In15.Cu" signal "IN6")
		(34 "In16.Cu" signal "GND7")
		(2 "B.Cu" signal "BOTTOM")
		(9 "F.Adhes" user "F.Adhesive")
		(11 "B.Adhes" user "B.Adhesive")
		(13 "F.Paste" user "Package Geometry/Pastemask Top")
		(15 "B.Paste" user "Package Geometry/Pastemask Bottom")
		(5 "F.SilkS" user "Ref Des/Silkscreen Top")
		(7 "B.SilkS" user "Ref Des/Silkscreen Bottom")
		(1 "F.Mask" user "Board Geometry/Soldermask Top")
		(3 "B.Mask" user "Board Geometry/Soldermask Bottom")
		(17 "Dwgs.User" user "User.Drawings")
		(19 "Cmts.User" user "User.Comments")
		(21 "Eco1.User" user "User.Eco1")
		(23 "Eco2.User" user "User.Eco2")
		(25 "Edge.Cuts" user "Board Geometry/Outline")
		(27 "Margin" user)
		(31 "F.CrtYd" user "Package Geometry/Place Bound Top")
		(29 "B.CrtYd" user "Package Geometry/Place Bound Bottom")
		(35 "F.Fab" user "Ref Des/Assembly Top")
		(33 "B.Fab" user "Ref Des/Assembly Bottom")
	)
	(footprint ""
		(layer "F.Cu")
		(at 147.199096 -65.321434 180)
		(property "Reference" "R1619"
			(at 0 0 180)
			(layer "F.SilkS")
			(hide yes)
			(effects
				(font
					(size 1.27 1.27)
				)
			)
		)
		(property "Value" ""
			(at 0 0 180)
			(layer "F.Fab")
			(effects
				(font
					(size 1.27 1.27)
				)
			)
		)
		(duplicate_pad_numbers_are_jumpers no)
		(fp_line
			(start 0.7874 0.4064)
			(end -0.7874 0.4064)
			(stroke
				(width 0.1524)
				(type default)
			)
			(layer "F.SilkS")
		)
		(fp_line
			(start 0.7874 -0.4064)
			(end 0.7874 0.4064)
			(stroke
				(width 0.1524)
				(type default)
			)
			(layer "F.SilkS")
		)
		(fp_line
			(start -0.7874 0.4064)
			(end -0.7874 -0.4064)
			(stroke
				(width 0.1524)
				(type default)
			)
			(layer "F.SilkS")
		)
		(fp_line
			(start -0.7874 -0.4064)
			(end 0.7874 -0.4064)
			(stroke
				(width 0.1524)
				(type default)
			)
			(layer "F.SilkS")
		)
		(fp_line
			(start 0.67945 0.3048)
			(end 0.120396 0.3048)
			(stroke
				(width 0.1)
				(type default)
			)
			(layer "F.Fab")
		)
		(fp_line
			(start 0.67945 -0.3048)
			(end 0.67945 0.3048)
			(stroke
				(width 0.1)
				(type default)
			)
			(layer "F.Fab")
		)
		(fp_line
			(start 0.12065 -0.2794)
			(end 0.12065 -0.3048)
			(stroke
				(width 0.1)
				(type default)
			)
			(layer "F.Fab")
		)
		(fp_line
			(start 0.12065 -0.3048)
			(end 0.67945 -0.3048)
			(stroke
				(width 0.1)
				(type default)
			)
			(layer "F.Fab")
		)
		(fp_line
			(start 0.120396 0.3048)
			(end 0.120396 0.2794)
			(stroke
				(width 0.1)
				(type default)
			)
			(layer "F.Fab")
		)
		(fp_line
			(start 0.120396 0.2794)
			(end -0.12065 0.2794)
			(stroke
				(width 0.1)
				(type default)
			)
			(layer "F.Fab")
		)
		(fp_line
			(start -0.12065 0.3048)
			(end -0.67945 0.3048)
			(stroke
				(width 0.1)
				(type default)
			)
			(layer "F.Fab")
		)
		(fp_line
			(start -0.12065 0.2794)
			(end -0.12065 0.3048)
			(stroke
				(width 0.1)
				(type default)
			)
			(layer "F.Fab")
		)
		(fp_line
			(start -0.12065 -0.2794)
			(end 0.12065 -0.2794)
			(stroke
				(width 0.1)
				(type default)
			)
			(layer "F.Fab")
		)
		(fp_line
			(start -0.12065 -0.305054)
			(end -0.12065 -0.2794)
			(stroke
				(width 0.1)
				(type default)
			)
			(layer "F.Fab")
		)
		(fp_line
			(start -0.67945 0.3048)
			(end -0.67945 -0.305054)
			(stroke
				(width 0.1)
				(type default)
			)
			(layer "F.Fab")
		)
		(fp_line
			(start -0.67945 -0.305054)
			(end -0.12065 -0.305054)
			(stroke
				(width 0.1)
				(type default)
			)
			(layer "F.Fab")
		)
		(pad "1" smd circle
			(at -0.40005 0 180)
			(size 0 0)
			(layers "F.Cu" "F.Mask" "F.Paste")
			(net "JTAG_BMC_OE")
		)
		(pad "2" smd circle
			(at 0.40005 0 180)
			(size 0 0)
			(layers "F.Cu" "F.Mask" "F.Paste")
			(net "JTAG_BMC_R_D_OE")
		)
	)
	(footprint ""
		(layer "F.Cu")
		(at 92.387674 -165.962076 180)
		(property "Reference" "PC273"
			(at -0.974852 -2.775204 0)
			(unlocked yes)
			(layer "F.SilkS")
			(effects
				(font
					(size 0.7874 0.5842)
					(thickness 0.1524)
				)
				(justify left)
			)
		)
		(property "Value" ""
			(at 0 0 180)
			(layer "F.Fab")
			(effects
				(font
					(size 1.27 1.27)
				)
			)
		)
		(duplicate_pad_numbers_are_jumpers no)
		(fp_line
			(start -3.400044 1.249934)
			(end 3.400044 1.249934)
			(stroke
				(width 0.1524)
				(type default)
			)
			(layer "F.SilkS")
		)
		(fp_circle
			(center 0 1.249934)
			(end -3.400044 1.249934)
			(stroke
				(width 0.1524)
				(type default)
			)
			(fill no)
			(layer "F.SilkS")
		)
		(fp_poly
			(pts
				(arc
					(start 3.400044 1.249934)
					(mid 0 4.649978)
					(end -3.400044 1.249934)
				)
			)
			(stroke
				(width 0)
				(type default)
			)
			(fill yes)
			(layer "F.SilkS")
		)
		(fp_circle
			(center 0 1.249934)
			(end -3.400044 1.249934)
			(stroke
				(width 0.1)
				(type default)
			)
			(fill no)
			(layer "F.Fab")
		)
		(pad "1" thru_hole rect
			(at 0 0 180)
			(size 1.524 1.524)
			(drill 1.016)
			(layers "*.Cu" "*.Mask")
			(remove_unused_layers no)
			(net "SW_P12V_AUX_PVDDCR_CPU0_P1_FLT")
			(clearance 0)
			(padstack
				(mode front_inner_back)
				(layer "Inner"
					(shape circle)
					(size 1.524 1.524)
					(clearance 0)
				)
				(layer "B.Cu"
					(shape rect)
					(size 1.524 1.524)
					(clearance 0)
				)
			)
		)
		(pad "2" thru_hole circle
			(at 0 2.500122 180)
			(size 1.524 1.524)
			(drill 1.016)
			(layers "*.Cu" "*.Mask")
			(remove_unused_layers no)
			(net "GND")
			(clearance 0)
		)
	)
	(footprint ""
		(layer "F.Cu")
		(at 247.499632 -40.903144 90)
		(property "Reference" "PD112"
			(at -3.422142 -2.350008 90)
			(unlocked yes)
			(layer "F.SilkS")
			(effects
				(font
					(size 0.7874 0.5842)
					(thickness 0.1524)
				)
				(justify left)
			)
		)
		(property "Value" ""
			(at 0 0 90)
			(layer "F.Fab")
			(effects
				(font
					(size 1.27 1.27)
				)
			)
		)
		(duplicate_pad_numbers_are_jumpers no)
		(fp_line
			(start 4.107942 -1.459992)
			(end 4.107942 1.459992)
			(stroke
				(width 0.1524)
				(type default)
			)
			(layer "F.SilkS")
		)
		(fp_line
			(start -3.400044 -1.459992)
			(end 4.107942 -1.459992)
			(stroke
				(width 0.1524)
				(type default)
			)
			(layer "F.SilkS")
		)
		(fp_line
			(start 4.107942 1.459992)
			(end -3.400044 1.459992)
			(stroke
				(width 0.1524)
				(type default)
			)
			(layer "F.SilkS")
		)
		(fp_line
			(start -3.400044 1.459992)
			(end -3.400044 -1.459992)
			(stroke
				(width 0.1524)
				(type default)
			)
			(layer "F.SilkS")
		)
		(fp_line
			(start 2.29997 -1.459992)
			(end 2.29997 1.459992)
			(stroke
				(width 0.1)
				(type default)
			)
			(layer "F.Fab")
		)
		(fp_line
			(start -2.29997 -1.459992)
			(end 2.29997 -1.459992)
			(stroke
				(width 0.1)
				(type default)
			)
			(layer "F.Fab")
		)
		(fp_line
			(start 2.29997 1.459992)
			(end -2.29997 1.459992)
			(stroke
				(width 0.1)
				(type default)
			)
			(layer "F.Fab")
		)
		(fp_line
			(start -2.29997 1.459992)
			(end -2.29997 -1.459992)
			(stroke
				(width 0.1)
				(type default)
			)
			(layer "F.Fab")
		)
		(fp_text user "+"
			(at -4.7752 -0.12065 90)
			(unlocked yes)
			(layer "F.SilkS")
			(effects
				(font
					(size 1.905 1.4224)
					(thickness 0.1524)
				)
				(justify left)
			)
		)
		(fp_text user "-"
			(at 5.245862 0.80264 270)
			(unlocked yes)
			(layer "F.SilkS")
			(effects
				(font
					(size 1.905 1.4224)
					(thickness 0.1524)
				)
				(justify left)
			)
		)
		(fp_text user "+"
			(at -4.7752 -0.12065 90)
			(unlocked yes)
			(layer "F.Fab")
			(effects
				(font
					(size 1.905 1.4224)
					(thickness 0.1524)
				)
				(justify left)
			)
		)
		(fp_text user "-"
			(at 5.4102 0.29845 270)
			(unlocked yes)
			(layer "F.Fab")
			(effects
				(font
					(size 1.905 1.4224)
					(thickness 0.1524)
				)
				(justify left)
			)
		)
		(pad "A" smd rect
			(at -1.999996 0 180)
			(size 1.7018 2.5146)
			(layers "F.Cu" "F.Mask" "F.Paste")
			(net "GND")
		)
		(pad "C" smd rect
			(at 1.999996 0 180)
			(size 1.7018 2.5146)
			(layers "F.Cu" "F.Mask" "F.Paste")
			(net "P12V_E1S_0")
		)
	)
)
